# S9S_MB_2U (Grand Teton) — schematic netlist excerpt (pin names and nets, part order shuffled) for the footprints in the layout excerpt that follows; sources: Cadence DE-HDL packaged netlist, KiCad conversion of 03242023_DA0F0TMBIJ0_F0T_Motherboard_J_brd_V01_OCP.brd

R4667  Q_RES  160K 1% EMPTY  pkg 0402LF  page 306 : A = HSC_CSOUT ; B = A_HSC_LOW
PC634  Q_CAP  3300PF 50V 10% X7R  pkg 0402  page 279 : A = SW_P12V_PVCCINFAON_CPU0_FLT ; B = GND

(kicad_pcb
	(version 20260206)
	(generator "pcbnew")
	(generator_version "10.0")
	(general
		(thickness 1.6)
		(legacy_teardrops no)
	)
	(paper "A4")
	(title_block
		(title "03242023_DA0F0TMBIJ0_F0T_Motherboard_J_brd_V01_OCP.brd")
		(comment 1 "Grand Teton / footprints 2382-2383 of 6105")
	)
	(layers
		(0 "F.Cu" signal "TOP")
		(4 "In1.Cu" signal "GND")
		(6 "In2.Cu" signal "IN1")
		(8 "In3.Cu" signal "GND1")
		(10 "In4.Cu" signal "IN2")
		(12 "In5.Cu" signal "GND2")
		(14 "In6.Cu" signal "IN3")
		(16 "In7.Cu" signal "GND3")
		(18 "In8.Cu" signal "VCC")
		(20 "In9.Cu" signal "VCC1")
		(22 "In10.Cu" signal "GND4")
		(24 "In11.Cu" signal "IN4")
		(26 "In12.Cu" signal "GND5")
		(28 "In13.Cu" signal "IN5")
		(30 "In14.Cu" signal "GND6")
		(32 "In15.Cu" signal "IN6")
		(34 "In16.Cu" signal "GND7")
		(2 "B.Cu" signal "BOTTOM")
		(9 "F.Adhes" user "F.Adhesive")
		(11 "B.Adhes" user "B.Adhesive")
		(13 "F.Paste" user "Package Geometry/Pastemask Top")
		(15 "B.Paste" user "Package Geometry/Pastemask Bottom")
		(5 "F.SilkS" user "Ref Des/Silkscreen Top")
		(7 "B.SilkS" user "Ref Des/Silkscreen Bottom")
		(1 "F.Mask" user "Board Geometry/Soldermask Top")
		(3 "B.Mask" user "Board Geometry/Soldermask Bottom")
		(17 "Dwgs.User" user "User.Drawings")
		(19 "Cmts.User" user "User.Comments")
		(21 "Eco1.User" user "User.Eco1")
		(23 "Eco2.User" user "User.Eco2")
		(25 "Edge.Cuts" user "Board Geometry/Outline")
		(27 "Margin" user)
		(31 "F.CrtYd" user "Package Geometry/Place Bound Top")
		(29 "B.CrtYd" user "Package Geometry/Place Bound Bottom")
		(35 "F.Fab" user "Ref Des/Assembly Top")
		(33 "B.Fab" user "Ref Des/Assembly Bottom")
	)
	(footprint ""
		(layer "F.Cu")
		(at 416.097974 -158.61665 180)
		(property "Reference" "PC634"
			(at 0 0 180)
			(layer "F.SilkS")
			(hide yes)
			(effects
				(font
					(size 1.27 1.27)
				)
			)
		)
		(property "Value" ""
			(at 0 0 180)
			(layer "F.Fab")
			(effects
				(font
					(size 1.27 1.27)
				)
			)
		)
		(duplicate_pad_numbers_are_jumpers no)
		(fp_line
			(start 0.7874 0.4064)
			(end -0.7874 0.4064)
			(stroke
				(width 0.1524)
				(type default)
			)
			(layer "F.SilkS")
		)
		(fp_line
			(start 0.7874 -0.4064)
			(end 0.7874 0.4064)
			(stroke
				(width 0.1524)
				(type default)
			)
			(layer "F.SilkS")
		)
		(fp_line
			(start -0.7874 0.4064)
			(end -0.7874 -0.4064)
			(stroke
				(width 0.1524)
				(type default)
			)
			(layer "F.SilkS")
		)
		(fp_line
			(start -0.7874 -0.4064)
			(end 0.7874 -0.4064)
			(stroke
				(width 0.1524)
				(type default)
			)
			(layer "F.SilkS")
		)
		(fp_line
			(start 0.67945 0.3048)
			(end 0.120396 0.3048)
			(stroke
				(width 0.1)
				(type default)
			)
			(layer "F.Fab")
		)
		(fp_line
			(start 0.67945 -0.3048)
			(end 0.67945 0.3048)
			(stroke
				(width 0.1)
				(type default)
			)
			(layer "F.Fab")
		)
		(fp_line
			(start 0.12065 -0.2794)
			(end 0.12065 -0.3048)
			(stroke
				(width 0.1)
				(type default)
			)
			(layer "F.Fab")
		)
		(fp_line
			(start 0.12065 -0.3048)
			(end 0.67945 -0.3048)
			(stroke
				(width 0.1)
				(type default)
			)
			(layer "F.Fab")
		)
		(fp_line
			(start 0.120396 0.3048)
			(end 0.120396 0.2794)
			(stroke
				(width 0.1)
				(type default)
			)
			(layer "F.Fab")
		)
		(fp_line
			(start 0.120396 0.2794)
			(end -0.12065 0.2794)
			(stroke
				(width 0.1)
				(type default)
			)
			(layer "F.Fab")
		)
		(fp_line
			(start -0.12065 0.3048)
			(end -0.67945 0.3048)
			(stroke
				(width 0.1)
				(type default)
			)
			(layer "F.Fab")
		)
		(fp_line
			(start -0.12065 0.2794)
			(end -0.12065 0.3048)
			(stroke
				(width 0.1)
				(type default)
			)
			(layer "F.Fab")
		)
		(fp_line
			(start -0.12065 -0.2794)
			(end 0.12065 -0.2794)
			(stroke
				(width 0.1)
				(type default)
			)
			(layer "F.Fab")
		)
		(fp_line
			(start -0.12065 -0.305054)
			(end -0.12065 -0.2794)
			(stroke
				(width 0.1)
				(type default)
			)
			(layer "F.Fab")
		)
		(fp_line
			(start -0.67945 0.3048)
			(end -0.67945 -0.305054)
			(stroke
				(width 0.1)
				(type default)
			)
			(layer "F.Fab")
		)
		(fp_line
			(start -0.67945 -0.305054)
			(end -0.12065 -0.305054)
			(stroke
				(width 0.1)
				(type default)
			)
			(layer "F.Fab")
		)
		(pad "1" smd circle
			(at -0.40005 0 180)
			(size 0 0)
			(layers "F.Cu" "F.Mask" "F.Paste")
			(net "SW_P12V_PVCCINFAON_CPU0_FLT")
		)
		(pad "2" smd circle
			(at 0.40005 0 180)
			(size 0 0)
			(layers "F.Cu" "F.Mask" "F.Paste")
			(net "GND")
		)
	)
	(footprint ""
		(layer "F.Cu")
		(at 280.278078 -417.2839 90)
		(property "Reference" "R4667"
			(at 0 0 90)
			(layer "F.SilkS")
			(hide yes)
			(effects
				(font
					(size 1.27 1.27)
				)
			)
		)
		(property "Value" ""
			(at 0 0 90)
			(layer "F.Fab")
			(effects
				(font
					(size 1.27 1.27)
				)
			)
		)
		(duplicate_pad_numbers_are_jumpers no)
		(fp_line
			(start 0.7874 -0.4064)
			(end 0.7874 0.4064)
			(stroke
				(width 0.1524)
				(type default)
			)
			(layer "F.SilkS")
		)
		(fp_line
			(start -0.7874 -0.4064)
			(end 0.7874 -0.4064)
			(stroke
				(width 0.1524)
				(type default)
			)
			(layer "F.SilkS")
		)
		(fp_line
			(start 0.7874 0.4064)
			(end -0.7874 0.4064)
			(stroke
				(width 0.1524)
				(type default)
			)
			(layer "F.SilkS")
		)
		(fp_line
			(start -0.7874 0.4064)
			(end -0.7874 -0.4064)
			(stroke
				(width 0.1524)
				(type default)
			)
			(layer "F.SilkS")
		)
		(fp_line
			(start -0.12065 -0.305054)
			(end -0.12065 -0.2794)
			(stroke
				(width 0.1)
				(type default)
			)
			(layer "F.Fab")
		)
		(fp_line
			(start -0.67945 -0.305054)
			(end -0.12065 -0.305054)
			(stroke
				(width 0.1)
				(type default)
			)
			(layer "F.Fab")
		)
		(fp_line
			(start 0.67945 -0.3048)
			(end 0.67945 0.3048)
			(stroke
				(width 0.1)
				(type default)
			)
			(layer "F.Fab")
		)
		(fp_line
			(start 0.12065 -0.3048)
			(end 0.67945 -0.3048)
			(stroke
				(width 0.1)
				(type default)
			)
			(layer "F.Fab")
		)
		(fp_line
			(start 0.12065 -0.2794)
			(end 0.12065 -0.3048)
			(stroke
				(width 0.1)
				(type default)
			)
			(layer "F.Fab")
		)
		(fp_line
			(start -0.12065 -0.2794)
			(end 0.12065 -0.2794)
			(stroke
				(width 0.1)
				(type default)
			)
			(layer "F.Fab")
		)
		(fp_line
			(start 0.120396 0.2794)
			(end -0.12065 0.2794)
			(stroke
				(width 0.1)
				(type default)
			)
			(layer "F.Fab")
		)
		(fp_line
			(start -0.12065 0.2794)
			(end -0.12065 0.3048)
			(stroke
				(width 0.1)
				(type default)
			)
			(layer "F.Fab")
		)
		(fp_line
			(start 0.67945 0.3048)
			(end 0.120396 0.3048)
			(stroke
				(width 0.1)
				(type default)
			)
			(layer "F.Fab")
		)
		(fp_line
			(start 0.120396 0.3048)
			(end 0.120396 0.2794)
			(stroke
				(width 0.1)
				(type default)
			)
			(layer "F.Fab")
		)
		(fp_line
			(start -0.12065 0.3048)
			(end -0.67945 0.3048)
			(stroke
				(width 0.1)
				(type default)
			)
			(layer "F.Fab")
		)
		(fp_line
			(start -0.67945 0.3048)
			(end -0.67945 -0.305054)
			(stroke
				(width 0.1)
				(type default)
			)
			(layer "F.Fab")
		)
		(pad "1" smd circle
			(at -0.40005 0 90)
			(size 0 0)
			(layers "F.Cu" "F.Mask" "F.Paste")
			(net "HSC_CSOUT")
		)
		(pad "2" smd circle
			(at 0.40005 0 90)
			(size 0 0)
			(layers "F.Cu" "F.Mask" "F.Paste")
			(net "A_HSC_LOW")
		)
	)
)
